# T6G (Grand Teton) — schematic netlist excerpt (pin names and nets, part order shuffled) for the footprints in the layout excerpt that follows; sources: Cadence DE-HDL packaged netlist, KiCad conversion of 04192023_DAF0TMB3IC0_F0TG_MB_C_brd_V02_OCP.brd

R3036  Q_RES  33.2 1% CHIP  pkg 0402LF  page 130 : A = UART_BMC_BIC_R_BUF_RX ; B = UART_BMC_BIC_BUF_RX
PC6022  Q_CAP  100NF 50V 10% X7R  pkg C0402  page 270 : A = P1V2_AUX ; B = GND

(kicad_pcb
	(version 20260206)
	(generator "pcbnew")
	(generator_version "10.0")
	(general
		(thickness 1.6)
		(legacy_teardrops no)
	)
	(paper "A4")
	(title_block
		(title "04192023_DAF0TMB3IC0_F0TG_MB_C_brd_V02_OCP.brd")
		(comment 1 "Grand Teton / footprints 3588-3589 of 8354")
	)
	(layers
		(0 "F.Cu" signal "TOP")
		(4 "In1.Cu" signal "GND")
		(6 "In2.Cu" signal "IN1")
		(8 "In3.Cu" signal "GND1")
		(10 "In4.Cu" signal "IN2")
		(12 "In5.Cu" signal "GND2")
		(14 "In6.Cu" signal "IN3")
		(16 "In7.Cu" signal "GND3")
		(18 "In8.Cu" signal "VCC")
		(20 "In9.Cu" signal "VCC1")
		(22 "In10.Cu" signal "GND4")
		(24 "In11.Cu" signal "IN4")
		(26 "In12.Cu" signal "GND5")
		(28 "In13.Cu" signal "IN5")
		(30 "In14.Cu" signal "GND6")
		(32 "In15.Cu" signal "IN6")
		(34 "In16.Cu" signal "GND7")
		(2 "B.Cu" signal "BOTTOM")
		(9 "F.Adhes" user "F.Adhesive")
		(11 "B.Adhes" user "B.Adhesive")
		(13 "F.Paste" user "Package Geometry/Pastemask Top")
		(15 "B.Paste" user "Package Geometry/Pastemask Bottom")
		(5 "F.SilkS" user "Ref Des/Silkscreen Top")
		(7 "B.SilkS" user "Ref Des/Silkscreen Bottom")
		(1 "F.Mask" user "Board Geometry/Soldermask Top")
		(3 "B.Mask" user "Board Geometry/Soldermask Bottom")
		(17 "Dwgs.User" user "User.Drawings")
		(19 "Cmts.User" user "User.Comments")
		(21 "Eco1.User" user "User.Eco1")
		(23 "Eco2.User" user "User.Eco2")
		(25 "Edge.Cuts" user "Board Geometry/Outline")
		(27 "Margin" user)
		(31 "F.CrtYd" user "Package Geometry/Place Bound Top")
		(29 "B.CrtYd" user "Package Geometry/Place Bound Bottom")
		(35 "F.Fab" user "Ref Des/Assembly Top")
		(33 "B.Fab" user "Ref Des/Assembly Bottom")
	)
	(footprint ""
		(layer "F.Cu")
		(at 130.231642 -71.303134 180)
		(property "Reference" "PC6022"
			(at 0 0 180)
			(layer "F.SilkS")
			(hide yes)
			(effects
				(font
					(size 1.27 1.27)
				)
			)
		)
		(property "Value" ""
			(at 0 0 180)
			(layer "F.Fab")
			(effects
				(font
					(size 1.27 1.27)
				)
			)
		)
		(duplicate_pad_numbers_are_jumpers no)
		(fp_line
			(start 0.7874 0.4064)
			(end -0.7874 0.4064)
			(stroke
				(width 0.1524)
				(type default)
			)
			(layer "F.SilkS")
		)
		(fp_line
			(start 0.7874 -0.4064)
			(end 0.7874 0.4064)
			(stroke
				(width 0.1524)
				(type default)
			)
			(layer "F.SilkS")
		)
		(fp_line
			(start -0.7874 0.4064)
			(end -0.7874 -0.4064)
			(stroke
				(width 0.1524)
				(type default)
			)
			(layer "F.SilkS")
		)
		(fp_line
			(start -0.7874 -0.4064)
			(end 0.7874 -0.4064)
			(stroke
				(width 0.1524)
				(type default)
			)
			(layer "F.SilkS")
		)
		(fp_line
			(start 0.67945 0.3048)
			(end 0.120396 0.3048)
			(stroke
				(width 0.1)
				(type default)
			)
			(layer "F.Fab")
		)
		(fp_line
			(start 0.67945 -0.3048)
			(end 0.67945 0.3048)
			(stroke
				(width 0.1)
				(type default)
			)
			(layer "F.Fab")
		)
		(fp_line
			(start 0.12065 -0.2794)
			(end 0.12065 -0.3048)
			(stroke
				(width 0.1)
				(type default)
			)
			(layer "F.Fab")
		)
		(fp_line
			(start 0.12065 -0.3048)
			(end 0.67945 -0.3048)
			(stroke
				(width 0.1)
				(type default)
			)
			(layer "F.Fab")
		)
		(fp_line
			(start 0.120396 0.3048)
			(end 0.120396 0.2794)
			(stroke
				(width 0.1)
				(type default)
			)
			(layer "F.Fab")
		)
		(fp_line
			(start 0.120396 0.2794)
			(end -0.12065 0.2794)
			(stroke
				(width 0.1)
				(type default)
			)
			(layer "F.Fab")
		)
		(fp_line
			(start -0.12065 0.3048)
			(end -0.67945 0.3048)
			(stroke
				(width 0.1)
				(type default)
			)
			(layer "F.Fab")
		)
		(fp_line
			(start -0.12065 0.2794)
			(end -0.12065 0.3048)
			(stroke
				(width 0.1)
				(type default)
			)
			(layer "F.Fab")
		)
		(fp_line
			(start -0.12065 -0.2794)
			(end 0.12065 -0.2794)
			(stroke
				(width 0.1)
				(type default)
			)
			(layer "F.Fab")
		)
		(fp_line
			(start -0.12065 -0.305054)
			(end -0.12065 -0.2794)
			(stroke
				(width 0.1)
				(type default)
			)
			(layer "F.Fab")
		)
		(fp_line
			(start -0.67945 0.3048)
			(end -0.67945 -0.305054)
			(stroke
				(width 0.1)
				(type default)
			)
			(layer "F.Fab")
		)
		(fp_line
			(start -0.67945 -0.305054)
			(end -0.12065 -0.305054)
			(stroke
				(width 0.1)
				(type default)
			)
			(layer "F.Fab")
		)
		(pad "1" smd circle
			(at -0.40005 0 180)
			(size 0 0)
			(layers "F.Cu" "F.Mask" "F.Paste")
			(net "P1V2_AUX")
		)
		(pad "2" smd circle
			(at 0.40005 0 180)
			(size 0 0)
			(layers "F.Cu" "F.Mask" "F.Paste")
			(net "GND")
		)
	)
	(footprint ""
		(layer "F.Cu")
		(at 360.76001 -417.313618)
		(property "Reference" "R3036"
			(at 0 0 0)
			(layer "F.SilkS")
			(hide yes)
			(effects
				(font
					(size 1.27 1.27)
				)
			)
		)
		(property "Value" ""
			(at 0 0 0)
			(layer "F.Fab")
			(effects
				(font
					(size 1.27 1.27)
				)
			)
		)
		(duplicate_pad_numbers_are_jumpers no)
		(fp_line
			(start -0.7874 -0.4064)
			(end 0.7874 -0.4064)
			(stroke
				(width 0.1524)
				(type default)
			)
			(layer "F.SilkS")
		)
		(fp_line
			(start -0.7874 0.4064)
			(end -0.7874 -0.4064)
			(stroke
				(width 0.1524)
				(type default)
			)
			(layer "F.SilkS")
		)
		(fp_line
			(start 0.7874 -0.4064)
			(end 0.7874 0.4064)
			(stroke
				(width 0.1524)
				(type default)
			)
			(layer "F.SilkS")
		)
		(fp_line
			(start 0.7874 0.4064)
			(end -0.7874 0.4064)
			(stroke
				(width 0.1524)
				(type default)
			)
			(layer "F.SilkS")
		)
		(fp_line
			(start -0.67945 -0.305054)
			(end -0.12065 -0.305054)
			(stroke
				(width 0.1)
				(type default)
			)
			(layer "F.Fab")
		)
		(fp_line
			(start -0.67945 0.3048)
			(end -0.67945 -0.305054)
			(stroke
				(width 0.1)
				(type default)
			)
			(layer "F.Fab")
		)
		(fp_line
			(start -0.12065 -0.305054)
			(end -0.12065 -0.2794)
			(stroke
				(width 0.1)
				(type default)
			)
			(layer "F.Fab")
		)
		(fp_line
			(start -0.12065 -0.2794)
			(end 0.12065 -0.2794)
			(stroke
				(width 0.1)
				(type default)
			)
			(layer "F.Fab")
		)
		(fp_line
			(start -0.12065 0.2794)
			(end -0.12065 0.3048)
			(stroke
				(width 0.1)
				(type default)
			)
			(layer "F.Fab")
		)
		(fp_line
			(start -0.12065 0.3048)
			(end -0.67945 0.3048)
			(stroke
				(width 0.1)
				(type default)
			)
			(layer "F.Fab")
		)
		(fp_line
			(start 0.120396 0.2794)
			(end -0.12065 0.2794)
			(stroke
				(width 0.1)
				(type default)
			)
			(layer "F.Fab")
		)
		(fp_line
			(start 0.120396 0.3048)
			(end 0.120396 0.2794)
			(stroke
				(width 0.1)
				(type default)
			)
			(layer "F.Fab")
		)
		(fp_line
			(start 0.12065 -0.3048)
			(end 0.67945 -0.3048)
			(stroke
				(width 0.1)
				(type default)
			)
			(layer "F.Fab")
		)
		(fp_line
			(start 0.12065 -0.2794)
			(end 0.12065 -0.3048)
			(stroke
				(width 0.1)
				(type default)
			)
			(layer "F.Fab")
		)
		(fp_line
			(start 0.67945 -0.3048)
			(end 0.67945 0.3048)
			(stroke
				(width 0.1)
				(type default)
			)
			(layer "F.Fab")
		)
		(fp_line
			(start 0.67945 0.3048)
			(end 0.120396 0.3048)
			(stroke
				(width 0.1)
				(type default)
			)
			(layer "F.Fab")
		)
		(pad "1" smd circle
			(at -0.40005 0)
			(size 0 0)
			(layers "F.Cu" "F.Mask" "F.Paste")
			(net "UART_BMC_BIC_R_BUF_RX")
		)
		(pad "2" smd circle
			(at 0.40005 0)
			(size 0 0)
			(layers "F.Cu" "F.Mask" "F.Paste")
			(net "UART_BMC_BIC_BUF_RX")
		)
	)
)
